M48
INCH,TZ
T01C.012
T02C.016
T03C.032
T04C.073
T05C.086
T06C.091
T07C.14
T08C.146
T09C.157
;EXTENTS: -109.149 -108.603 139.866 126.750 
;LEADER: 12 
;HEADER: 
;CODE  : ASCII 
;FILE  : 14545-sa.rou for board 14545-sa.brd
%
G90
F1
M16
T03
M16
G00X165173Y758543
G40
M15
G01X169473
M16
G00X165173Y585315
G40
M15
G01X169473
M16
G00X165173Y1164055
G40
M15
G01X169473
M16
G00X165173Y990827
G40
M15
G01X169473
M16
G00X165173Y1569567
G40
M15
G01X169473
M16
G00X165173Y1396339
G40
M15
G01X169473
M16
G00X165173Y1975079
G40
M15
G01X169473
M16
G00X165173Y1801850
G40
M15
G01X169473
M16
G00X893519Y353031
G40
M15
G01X897819
M16
G00X893519Y179803
G40
M15
G01X897819
M16
G00X893519Y758543
G40
M15
G01X897819
M16
G00X893519Y585315
G40
M15
G01X897819
M16
G00X893519Y1164055
G40
M15
G01X897819
M16
G00X893519Y990827
G40
M15
G01X897819
M16
G00X893519Y1569567
G40
M15
G01X897819
M16
G00X893519Y1396339
G40
M15
G01X897819
M16
G00X66748Y17047
G40
M15
G01X71048
M16
G00X66748Y190275
G40
M15
G01X71048
M16
G00X66748Y422559
G40
M15
G01X71048
M16
G00X66748Y595787
G40
M15
G01X71048
M16
G00X66748Y828070
G40
M15
G01X71048
M16
G00X66748Y1001299
G40
M15
G01X71048
M16
G00X66748Y1233583
G40
M15
G01X71048
M16
G00X66748Y1406811
G40
M15
G01X71048
M16
G00X66748Y1639095
G40
M15
G01X71048
M16
G00X66748Y1812323
G40
M15
G01X71048
M16
G00X165173Y353031
G40
M15
G01X169473
M16
G00X165173Y179803
G40
M15
G01X169473
M16
G00X893519Y1975079
G40
M15
G01X897819
M16
G00X893519Y1801850
G40
M15
G01X897819
M16
G40
M30
